# S9S_MB_2U (Grand Teton) — schematic netlist excerpt (pin names and nets, part order shuffled) for the footprints in the layout excerpt that follows; sources: Cadence DE-HDL packaged netlist, KiCad conversion of 03242023_DA0F0TMBIJ0_F0T_Motherboard_J_brd_V01_OCP.brd

PR3957  Q_RES  49.9 1% CHIP  pkg 0603LF  page 193 : A = P12V_AUX ; B = P12V_E1S_AVIN_PD_0
R3231  Q_RES  33.2 1% CHIP  pkg 0402LF  page 154 : A = OCP_SFF_AUX_PWR_EN ; B = OCP_SFF_AUX_PWR_EN_R4

(kicad_pcb
	(version 20260206)
	(generator "pcbnew")
	(generator_version "10.0")
	(general
		(thickness 1.6)
		(legacy_teardrops no)
	)
	(paper "A4")
	(title_block
		(title "03242023_DA0F0TMBIJ0_F0T_Motherboard_J_brd_V01_OCP.brd")
		(comment 1 "Grand Teton / footprints 271-272 of 6105")
	)
	(layers
		(0 "F.Cu" signal "TOP")
		(4 "In1.Cu" signal "GND")
		(6 "In2.Cu" signal "IN1")
		(8 "In3.Cu" signal "GND1")
		(10 "In4.Cu" signal "IN2")
		(12 "In5.Cu" signal "GND2")
		(14 "In6.Cu" signal "IN3")
		(16 "In7.Cu" signal "GND3")
		(18 "In8.Cu" signal "VCC")
		(20 "In9.Cu" signal "VCC1")
		(22 "In10.Cu" signal "GND4")
		(24 "In11.Cu" signal "IN4")
		(26 "In12.Cu" signal "GND5")
		(28 "In13.Cu" signal "IN5")
		(30 "In14.Cu" signal "GND6")
		(32 "In15.Cu" signal "IN6")
		(34 "In16.Cu" signal "GND7")
		(2 "B.Cu" signal "BOTTOM")
		(9 "F.Adhes" user "F.Adhesive")
		(11 "B.Adhes" user "B.Adhesive")
		(13 "F.Paste" user "Package Geometry/Pastemask Top")
		(15 "B.Paste" user "Package Geometry/Pastemask Bottom")
		(5 "F.SilkS" user "Ref Des/Silkscreen Top")
		(7 "B.SilkS" user "Ref Des/Silkscreen Bottom")
		(1 "F.Mask" user "Board Geometry/Soldermask Top")
		(3 "B.Mask" user "Board Geometry/Soldermask Bottom")
		(17 "Dwgs.User" user "User.Drawings")
		(19 "Cmts.User" user "User.Comments")
		(21 "Eco1.User" user "User.Eco1")
		(23 "Eco2.User" user "User.Eco2")
		(25 "Edge.Cuts" user "Board Geometry/Outline")
		(27 "Margin" user)
		(31 "F.CrtYd" user "Package Geometry/Place Bound Top")
		(29 "B.CrtYd" user "Package Geometry/Place Bound Bottom")
		(35 "F.Fab" user "Ref Des/Assembly Top")
		(33 "B.Fab" user "Ref Des/Assembly Bottom")
	)
	(footprint ""
		(layer "F.Cu")
		(at 249.52579 -53.424582 -90)
		(property "Reference" "PR3957"
			(at 0 0 270)
			(layer "F.SilkS")
			(hide yes)
			(effects
				(font
					(size 1.27 1.27)
				)
			)
		)
		(property "Value" ""
			(at 0 0 270)
			(layer "F.Fab")
			(effects
				(font
					(size 1.27 1.27)
				)
			)
		)
		(duplicate_pad_numbers_are_jumpers no)
		(fp_line
			(start -1.2954 0.5842)
			(end -1.2954 -0.5842)
			(stroke
				(width 0.1524)
				(type default)
			)
			(layer "F.SilkS")
		)
		(fp_line
			(start 1.2954 0.5842)
			(end -1.2954 0.5842)
			(stroke
				(width 0.1524)
				(type default)
			)
			(layer "F.SilkS")
		)
		(fp_line
			(start -1.2954 -0.5842)
			(end 1.2954 -0.5842)
			(stroke
				(width 0.1524)
				(type default)
			)
			(layer "F.SilkS")
		)
		(fp_line
			(start 1.2954 -0.5842)
			(end 1.2954 0.5842)
			(stroke
				(width 0.1524)
				(type default)
			)
			(layer "F.SilkS")
		)
		(fp_line
			(start -0.8636 0.4572)
			(end -0.8636 0.4318)
			(stroke
				(width 0.1)
				(type default)
			)
			(layer "F.Fab")
		)
		(fp_line
			(start 0.8636 0.4572)
			(end -0.8636 0.4572)
			(stroke
				(width 0.1)
				(type default)
			)
			(layer "F.Fab")
		)
		(fp_line
			(start -0.8636 0.4318)
			(end -0.8636 0.4064)
			(stroke
				(width 0.1)
				(type default)
			)
			(layer "F.Fab")
		)
		(fp_line
			(start -1.1938 0.4064)
			(end -1.1938 -0.406654)
			(stroke
				(width 0.1)
				(type default)
			)
			(layer "F.Fab")
		)
		(fp_line
			(start -0.8636 0.4064)
			(end -1.1938 0.4064)
			(stroke
				(width 0.1)
				(type default)
			)
			(layer "F.Fab")
		)
		(fp_line
			(start 0.8636 0.4064)
			(end 0.8636 0.4572)
			(stroke
				(width 0.1)
				(type default)
			)
			(layer "F.Fab")
		)
		(fp_line
			(start 1.1938 0.4064)
			(end 0.8636 0.4064)
			(stroke
				(width 0.1)
				(type default)
			)
			(layer "F.Fab")
		)
		(fp_line
			(start -1.1938 -0.406654)
			(end -0.8636 -0.406654)
			(stroke
				(width 0.1)
				(type default)
			)
			(layer "F.Fab")
		)
		(fp_line
			(start -0.8636 -0.406654)
			(end -0.8636 -0.4572)
			(stroke
				(width 0.1)
				(type default)
			)
			(layer "F.Fab")
		)
		(fp_line
			(start 0.8636 -0.406654)
			(end 1.1938 -0.406654)
			(stroke
				(width 0.1)
				(type default)
			)
			(layer "F.Fab")
		)
		(fp_line
			(start 1.1938 -0.406654)
			(end 1.1938 0.4064)
			(stroke
				(width 0.1)
				(type default)
			)
			(layer "F.Fab")
		)
		(fp_line
			(start -0.8636 -0.4572)
			(end 0.8636 -0.4572)
			(stroke
				(width 0.1)
				(type default)
			)
			(layer "F.Fab")
		)
		(fp_line
			(start 0.8636 -0.4572)
			(end 0.8636 -0.406654)
			(stroke
				(width 0.1)
				(type default)
			)
			(layer "F.Fab")
		)
		(pad "1" smd rect
			(at -0.7366 0 180)
			(size 0.7112 0.8128)
			(layers "F.Cu" "F.Mask" "F.Paste")
			(net "P12V_AUX")
		)
		(pad "2" smd rect
			(at 0.7366 0 180)
			(size 0.7112 0.8128)
			(layers "F.Cu" "F.Mask" "F.Paste")
			(net "P12V_E1S_AVIN_PD_0")
		)
	)
	(footprint ""
		(layer "F.Cu")
		(at 455.617834 -93.437964)
		(property "Reference" "R3231"
			(at 0 0 0)
			(layer "F.SilkS")
			(hide yes)
			(effects
				(font
					(size 1.27 1.27)
				)
			)
		)
		(property "Value" ""
			(at 0 0 0)
			(layer "F.Fab")
			(effects
				(font
					(size 1.27 1.27)
				)
			)
		)
		(duplicate_pad_numbers_are_jumpers no)
		(fp_line
			(start -0.7874 -0.4064)
			(end 0.7874 -0.4064)
			(stroke
				(width 0.1524)
				(type default)
			)
			(layer "F.SilkS")
		)
		(fp_line
			(start -0.7874 0.4064)
			(end -0.7874 -0.4064)
			(stroke
				(width 0.1524)
				(type default)
			)
			(layer "F.SilkS")
		)
		(fp_line
			(start 0.7874 -0.4064)
			(end 0.7874 0.4064)
			(stroke
				(width 0.1524)
				(type default)
			)
			(layer "F.SilkS")
		)
		(fp_line
			(start 0.7874 0.4064)
			(end -0.7874 0.4064)
			(stroke
				(width 0.1524)
				(type default)
			)
			(layer "F.SilkS")
		)
		(fp_line
			(start -0.67945 -0.305054)
			(end -0.12065 -0.305054)
			(stroke
				(width 0.1)
				(type default)
			)
			(layer "F.Fab")
		)
		(fp_line
			(start -0.67945 0.3048)
			(end -0.67945 -0.305054)
			(stroke
				(width 0.1)
				(type default)
			)
			(layer "F.Fab")
		)
		(fp_line
			(start -0.12065 -0.305054)
			(end -0.12065 -0.2794)
			(stroke
				(width 0.1)
				(type default)
			)
			(layer "F.Fab")
		)
		(fp_line
			(start -0.12065 -0.2794)
			(end 0.12065 -0.2794)
			(stroke
				(width 0.1)
				(type default)
			)
			(layer "F.Fab")
		)
		(fp_line
			(start -0.12065 0.2794)
			(end -0.12065 0.3048)
			(stroke
				(width 0.1)
				(type default)
			)
			(layer "F.Fab")
		)
		(fp_line
			(start -0.12065 0.3048)
			(end -0.67945 0.3048)
			(stroke
				(width 0.1)
				(type default)
			)
			(layer "F.Fab")
		)
		(fp_line
			(start 0.120396 0.2794)
			(end -0.12065 0.2794)
			(stroke
				(width 0.1)
				(type default)
			)
			(layer "F.Fab")
		)
		(fp_line
			(start 0.120396 0.3048)
			(end 0.120396 0.2794)
			(stroke
				(width 0.1)
				(type default)
			)
			(layer "F.Fab")
		)
		(fp_line
			(start 0.12065 -0.3048)
			(end 0.67945 -0.3048)
			(stroke
				(width 0.1)
				(type default)
			)
			(layer "F.Fab")
		)
		(fp_line
			(start 0.12065 -0.2794)
			(end 0.12065 -0.3048)
			(stroke
				(width 0.1)
				(type default)
			)
			(layer "F.Fab")
		)
		(fp_line
			(start 0.67945 -0.3048)
			(end 0.67945 0.3048)
			(stroke
				(width 0.1)
				(type default)
			)
			(layer "F.Fab")
		)
		(fp_line
			(start 0.67945 0.3048)
			(end 0.120396 0.3048)
			(stroke
				(width 0.1)
				(type default)
			)
			(layer "F.Fab")
		)
		(pad "1" smd circle
			(at -0.40005 0)
			(size 0 0)
			(layers "F.Cu" "F.Mask" "F.Paste")
			(net "OCP_SFF_AUX_PWR_EN")
		)
		(pad "2" smd circle
			(at 0.40005 0)
			(size 0 0)
			(layers "F.Cu" "F.Mask" "F.Paste")
			(net "OCP_SFF_AUX_PWR_EN_R4")
		)
	)
)
